(kicad_pcb
	(version 20240108)
	(generator "pcbnew")
	(generator_version "8.0")
	(general
		(thickness 1.6)
		(legacy_teardrops no)
	)
	(paper "A4")
	(title_block
		(title "Jetson Orin Baseboard OCuLink Expansion")
		(date "2025-03-18")
		(rev "1.1.0")
		(company "Antmicro Ltd")
		(comment 1 "www.antmicro.com")
		(comment 9 "footprints 91-94 of 119")
	)
	(layers
		(0 "F.Cu" signal)
		(1 "In1.Cu" signal)
		(2 "In2.Cu" signal)
		(31 "B.Cu" signal)
		(32 "B.Adhes" user "B.Adhesive")
		(33 "F.Adhes" user "F.Adhesive")
		(34 "B.Paste" user)
		(35 "F.Paste" user)
		(36 "B.SilkS" user "B.Silkscreen")
		(37 "F.SilkS" user "F.Silkscreen")
		(38 "B.Mask" user)
		(39 "F.Mask" user)
		(40 "Dwgs.User" user "User.Drawings")
		(41 "Cmts.User" user "User.Comments")
		(42 "Eco1.User" user "User.Eco1")
		(43 "Eco2.User" user "User.Eco2")
		(44 "Edge.Cuts" user)
		(45 "Margin" user)
		(46 "B.CrtYd" user "B.Courtyard")
		(47 "F.CrtYd" user "F.Courtyard")
		(48 "B.Fab" user)
		(49 "F.Fab" user)
	)
	(footprint "antmicro-footprints:C_0402_1005Metric"
		(layer "B.Cu")
		(at 118.275 127.913 -90)
		(descr "Capacitor SMD 0402")
		(tags "capacitor SMD 0402")
		(property "Reference" "C29"
			(at 1.627 -0.445 90)
			(layer "B.SilkS")
			(effects
				(font
					(size 0.7 0.7)
					(thickness 0.15)
				)
				(justify left bottom mirror)
			)
		)
		(property "Value" "C_100n_0402"
			(at -1.022927 -2.155213 90)
			(layer "B.Fab")
			(effects
				(font
					(size 0.7 0.7)
					(thickness 0.15)
				)
				(justify left bottom mirror)
			)
		)
		(property "Footprint" "antmicro-footprints:C_0402_1005Metric"
			(at 0 0 90)
			(layer "B.Fab")
			(hide yes)
			(effects
				(font
					(size 1.27 1.27)
					(thickness 0.15)
				)
				(justify mirror)
			)
		)
		(property "Datasheet" "https://www.murata.com/products/productdetail?partno=GRM155R61H104KE14%23"
			(at 0 0 90)
			(layer "B.Fab")
			(hide yes)
			(effects
				(font
					(size 1.27 1.27)
					(thickness 0.15)
				)
				(justify mirror)
			)
		)
		(property "Description" "SMD Multilayer Ceramic Capacitor, 0.1 µF, 50 V, 0402 [1005 Metric], ± 10%, X5R, GRM Series"
			(at 0 0 90)
			(layer "B.Fab")
			(hide yes)
			(effects
				(font
					(size 1.27 1.27)
					(thickness 0.15)
				)
				(justify mirror)
			)
		)
		(property "MPN" "GRM155R61H104KE14D"
			(at 0 0 90)
			(unlocked yes)
			(layer "B.Fab")
			(hide yes)
			(effects
				(font
					(size 1 1)
					(thickness 0.15)
				)
				(justify mirror)
			)
		)
		(property "Manufacturer" "Murata"
			(at 0 0 90)
			(unlocked yes)
			(layer "B.Fab")
			(hide yes)
			(effects
				(font
					(size 1 1)
					(thickness 0.15)
				)
				(justify mirror)
			)
		)
		(property "License" "Apache-2.0"
			(at 0 0 90)
			(unlocked yes)
			(layer "B.Fab")
			(hide yes)
			(effects
				(font
					(size 1 1)
					(thickness 0.15)
				)
				(justify mirror)
			)
		)
		(property "Author" "Antmicro"
			(at 0 0 90)
			(unlocked yes)
			(layer "B.Fab")
			(hide yes)
			(effects
				(font
					(size 1 1)
					(thickness 0.15)
				)
				(justify mirror)
			)
		)
		(property "Val" "100n"
			(at 0 0 90)
			(unlocked yes)
			(layer "B.Fab")
			(hide yes)
			(effects
				(font
					(size 1 1)
					(thickness 0.15)
				)
				(justify mirror)
			)
		)
		(property "Voltage" "50V"
			(at 0 0 90)
			(unlocked yes)
			(layer "B.Fab")
			(hide yes)
			(effects
				(font
					(size 1 1)
					(thickness 0.15)
				)
				(justify mirror)
			)
		)
		(property "Dielectric" "X5R"
			(at 0 0 90)
			(unlocked yes)
			(layer "B.Fab")
			(hide yes)
			(effects
				(font
					(size 1 1)
					(thickness 0.15)
				)
				(justify mirror)
			)
		)
		(property "Public" "False"
			(at 0 0 90)
			(unlocked yes)
			(layer "B.Fab")
			(hide yes)
			(effects
				(font
					(size 1 1)
					(thickness 0.15)
				)
				(justify mirror)
			)
		)
		(sheetname "Root")
		(sheetfile "jetson-orin-baseboard-oculink-expansion.kicad_sch")
		(attr smd)
		(fp_rect
			(start -0.925 0.47)
			(end 0.925 -0.47)
			(stroke
				(width 0.05)
				(type default)
			)
			(fill none)
			(layer "B.CrtYd")
		)
		(fp_line
			(start -0.494 0.25)
			(end -0.494 -0.248)
			(stroke
				(width 0.15)
				(type solid)
			)
			(layer "B.Fab")
		)
		(fp_line
			(start 0.504 0.25)
			(end -0.494 0.25)
			(stroke
				(width 0.15)
				(type solid)
			)
			(layer "B.Fab")
		)
		(fp_line
			(start -0.494 -0.248)
			(end 0.504 -0.248)
			(stroke
				(width 0.15)
				(type solid)
			)
			(layer "B.Fab")
		)
		(fp_line
			(start 0.504 -0.248)
			(end 0.504 0.25)
			(stroke
				(width 0.15)
				(type solid)
			)
			(layer "B.Fab")
		)
		(fp_text user "Author: Antmicro"
			(at -0.939 -3.399 90)
			(layer "B.Fab")
			(hide yes)
			(effects
				(font
					(size 0.7 0.7)
					(thickness 0.15)
				)
				(justify left bottom mirror)
			)
		)
		(fp_text user "License: Apache-2.0"
			(at -0.939 -5.799 90)
			(layer "B.Fab")
			(hide yes)
			(effects
				(font
					(size 0.7 0.7)
					(thickness 0.15)
				)
				(justify left bottom mirror)
			)
		)
		(fp_text user "${REFERENCE}"
			(at -0.939 -4.599 90)
			(layer "B.Fab")
			(hide yes)
			(effects
				(font
					(size 0.7 0.7)
					(thickness 0.15)
				)
				(justify left bottom mirror)
			)
		)
		(pad "1" smd roundrect
			(at -0.48 0 270)
			(size 0.59 0.64)
			(layers "B.Cu" "B.Paste" "B.Mask")
			(roundrect_rratio 0.25)
			(net 51 "GND")
			(pintype "passive")
		)
		(pad "2" smd roundrect
			(at 0.48 0 270)
			(size 0.59 0.64)
			(layers "B.Cu" "B.Paste" "B.Mask")
			(roundrect_rratio 0.25)
			(net 23 "+3V3")
			(pintype "passive")
		)
	)
	(footprint "antmicro-footprints:C_0402_1005Metric"
		(layer "B.Cu")
		(at 125.005 114.569251 90)
		(descr "Capacitor SMD 0402")
		(tags "capacitor SMD 0402")
		(property "Reference" "C11"
			(at 1.779251 -0.385 90)
			(layer "B.SilkS")
			(effects
				(font
					(size 0.7 0.7)
					(thickness 0.15)
				)
				(justify right top mirror)
			)
		)
		(property "Value" "C_100n_0402"
			(at -1.022927 -2.155213 90)
			(layer "B.Fab")
			(effects
				(font
					(size 0.7 0.7)
					(thickness 0.15)
				)
				(justify right top mirror)
			)
		)
		(property "Footprint" "antmicro-footprints:C_0402_1005Metric"
			(at 0 0 90)
			(layer "B.Fab")
			(hide yes)
			(effects
				(font
					(size 1.27 1.27)
					(thickness 0.15)
				)
				(justify mirror)
			)
		)
		(property "Datasheet" "https://www.murata.com/products/productdetail?partno=GRM155R61H104KE14%23"
			(at 0 0 90)
			(layer "B.Fab")
			(hide yes)
			(effects
				(font
					(size 1.27 1.27)
					(thickness 0.15)
				)
				(justify mirror)
			)
		)
		(property "Description" "SMD Multilayer Ceramic Capacitor, 0.1 µF, 50 V, 0402 [1005 Metric], ± 10%, X5R, GRM Series"
			(at 0 0 90)
			(layer "B.Fab")
			(hide yes)
			(effects
				(font
					(size 1.27 1.27)
					(thickness 0.15)
				)
				(justify mirror)
			)
		)
		(property "MPN" "GRM155R61H104KE14D"
			(at 0 0 -90)
			(unlocked yes)
			(layer "B.Fab")
			(hide yes)
			(effects
				(font
					(size 1 1)
					(thickness 0.15)
				)
				(justify mirror)
			)
		)
		(property "Manufacturer" "Murata"
			(at 0 0 -90)
			(unlocked yes)
			(layer "B.Fab")
			(hide yes)
			(effects
				(font
					(size 1 1)
					(thickness 0.15)
				)
				(justify mirror)
			)
		)
		(property "License" "Apache-2.0"
			(at 0 0 -90)
			(unlocked yes)
			(layer "B.Fab")
			(hide yes)
			(effects
				(font
					(size 1 1)
					(thickness 0.15)
				)
				(justify mirror)
			)
		)
		(property "Author" "Antmicro"
			(at 0 0 -90)
			(unlocked yes)
			(layer "B.Fab")
			(hide yes)
			(effects
				(font
					(size 1 1)
					(thickness 0.15)
				)
				(justify mirror)
			)
		)
		(property "Val" "100n"
			(at 0 0 -90)
			(unlocked yes)
			(layer "B.Fab")
			(hide yes)
			(effects
				(font
					(size 1 1)
					(thickness 0.15)
				)
				(justify mirror)
			)
		)
		(property "Voltage" "50V"
			(at 0 0 -90)
			(unlocked yes)
			(layer "B.Fab")
			(hide yes)
			(effects
				(font
					(size 1 1)
					(thickness 0.15)
				)
				(justify mirror)
			)
		)
		(property "Dielectric" "X5R"
			(at 0 0 -90)
			(unlocked yes)
			(layer "B.Fab")
			(hide yes)
			(effects
				(font
					(size 1 1)
					(thickness 0.15)
				)
				(justify mirror)
			)
		)
		(property "Public" "False"
			(at 0 0 -90)
			(unlocked yes)
			(layer "B.Fab")
			(hide yes)
			(effects
				(font
					(size 1 1)
					(thickness 0.15)
				)
				(justify mirror)
			)
		)
		(sheetname "Root")
		(sheetfile "jetson-orin-baseboard-oculink-expansion.kicad_sch")
		(attr smd)
		(fp_rect
			(start -0.925 0.47)
			(end 0.925 -0.47)
			(stroke
				(width 0.05)
				(type default)
			)
			(fill none)
			(layer "B.CrtYd")
		)
		(fp_line
			(start 0.504 -0.248)
			(end 0.504 0.25)
			(stroke
				(width 0.15)
				(type solid)
			)
			(layer "B.Fab")
		)
		(fp_line
			(start -0.494 -0.248)
			(end 0.504 -0.248)
			(stroke
				(width 0.15)
				(type solid)
			)
			(layer "B.Fab")
		)
		(fp_line
			(start 0.504 0.25)
			(end -0.494 0.25)
			(stroke
				(width 0.15)
				(type solid)
			)
			(layer "B.Fab")
		)
		(fp_line
			(start -0.494 0.25)
			(end -0.494 -0.248)
			(stroke
				(width 0.15)
				(type solid)
			)
			(layer "B.Fab")
		)
		(fp_text user "License: Apache-2.0"
			(at -0.939 -5.799 90)
			(layer "B.Fab")
			(hide yes)
			(effects
				(font
					(size 0.7 0.7)
					(thickness 0.15)
				)
				(justify right top mirror)
			)
		)
		(fp_text user "${REFERENCE}"
			(at -0.939 -4.599 90)
			(layer "B.Fab")
			(hide yes)
			(effects
				(font
					(size 0.7 0.7)
					(thickness 0.15)
				)
				(justify right top mirror)
			)
		)
		(fp_text user "Author: Antmicro"
			(at -0.939 -3.399 90)
			(layer "B.Fab")
			(hide yes)
			(effects
				(font
					(size 0.7 0.7)
					(thickness 0.15)
				)
				(justify right top mirror)
			)
		)
		(pad "1" smd roundrect
			(at -0.48 0 90)
			(size 0.59 0.64)
			(layers "B.Cu" "B.Paste" "B.Mask")
			(roundrect_rratio 0.25)
			(net 51 "GND")
			(pintype "passive")
		)
		(pad "2" smd roundrect
			(at 0.48 0 90)
			(size 0.59 0.64)
			(layers "B.Cu" "B.Paste" "B.Mask")
			(roundrect_rratio 0.25)
			(net 23 "+3V3")
			(pintype "passive")
		)
	)
	(footprint "antmicro-footprints:C_0402_1005Metric"
		(layer "B.Cu")
		(at 118.275 125.795 90)
		(descr "Capacitor SMD 0402")
		(tags "capacitor SMD 0402")
		(property "Reference" "C30"
			(at 1.605 -0.375 90)
			(layer "B.SilkS")
			(effects
				(font
					(size 0.7 0.7)
					(thickness 0.15)
				)
				(justify right top mirror)
			)
		)
		(property "Value" "C_100n_0402"
			(at -1.022927 -2.155213 90)
			(layer "B.Fab")
			(effects
				(font
					(size 0.7 0.7)
					(thickness 0.15)
				)
				(justify right top mirror)
			)
		)
		(property "Footprint" "antmicro-footprints:C_0402_1005Metric"
			(at 0 0 90)
			(layer "B.Fab")
			(hide yes)
			(effects
				(font
					(size 1.27 1.27)
					(thickness 0.15)
				)
				(justify mirror)
			)
		)
		(property "Datasheet" "https://www.murata.com/products/productdetail?partno=GRM155R61H104KE14%23"
			(at 0 0 90)
			(layer "B.Fab")
			(hide yes)
			(effects
				(font
					(size 1.27 1.27)
					(thickness 0.15)
				)
				(justify mirror)
			)
		)
		(property "Description" "SMD Multilayer Ceramic Capacitor, 0.1 µF, 50 V, 0402 [1005 Metric], ± 10%, X5R, GRM Series"
			(at 0 0 90)
			(layer "B.Fab")
			(hide yes)
			(effects
				(font
					(size 1.27 1.27)
					(thickness 0.15)
				)
				(justify mirror)
			)
		)
		(property "MPN" "GRM155R61H104KE14D"
			(at 0 0 -90)
			(unlocked yes)
			(layer "B.Fab")
			(hide yes)
			(effects
				(font
					(size 1 1)
					(thickness 0.15)
				)
				(justify mirror)
			)
		)
		(property "Manufacturer" "Murata"
			(at 0 0 -90)
			(unlocked yes)
			(layer "B.Fab")
			(hide yes)
			(effects
				(font
					(size 1 1)
					(thickness 0.15)
				)
				(justify mirror)
			)
		)
		(property "License" "Apache-2.0"
			(at 0 0 -90)
			(unlocked yes)
			(layer "B.Fab")
			(hide yes)
			(effects
				(font
					(size 1 1)
					(thickness 0.15)
				)
				(justify mirror)
			)
		)
		(property "Author" "Antmicro"
			(at 0 0 -90)
			(unlocked yes)
			(layer "B.Fab")
			(hide yes)
			(effects
				(font
					(size 1 1)
					(thickness 0.15)
				)
				(justify mirror)
			)
		)
		(property "Val" "100n"
			(at 0 0 -90)
			(unlocked yes)
			(layer "B.Fab")
			(hide yes)
			(effects
				(font
					(size 1 1)
					(thickness 0.15)
				)
				(justify mirror)
			)
		)
		(property "Voltage" "50V"
			(at 0 0 -90)
			(unlocked yes)
			(layer "B.Fab")
			(hide yes)
			(effects
				(font
					(size 1 1)
					(thickness 0.15)
				)
				(justify mirror)
			)
		)
		(property "Dielectric" "X5R"
			(at 0 0 -90)
			(unlocked yes)
			(layer "B.Fab")
			(hide yes)
			(effects
				(font
					(size 1 1)
					(thickness 0.15)
				)
				(justify mirror)
			)
		)
		(property "Public" "False"
			(at 0 0 -90)
			(unlocked yes)
			(layer "B.Fab")
			(hide yes)
			(effects
				(font
					(size 1 1)
					(thickness 0.15)
				)
				(justify mirror)
			)
		)
		(sheetname "Root")
		(sheetfile "jetson-orin-baseboard-oculink-expansion.kicad_sch")
		(attr smd)
		(fp_rect
			(start -0.925 0.47)
			(end 0.925 -0.47)
			(stroke
				(width 0.05)
				(type default)
			)
			(fill none)
			(layer "B.CrtYd")
		)
		(fp_line
			(start 0.504 -0.248)
			(end 0.504 0.25)
			(stroke
				(width 0.15)
				(type solid)
			)
			(layer "B.Fab")
		)
		(fp_line
			(start -0.494 -0.248)
			(end 0.504 -0.248)
			(stroke
				(width 0.15)
				(type solid)
			)
			(layer "B.Fab")
		)
		(fp_line
			(start 0.504 0.25)
			(end -0.494 0.25)
			(stroke
				(width 0.15)
				(type solid)
			)
			(layer "B.Fab")
		)
		(fp_line
			(start -0.494 0.25)
			(end -0.494 -0.248)
			(stroke
				(width 0.15)
				(type solid)
			)
			(layer "B.Fab")
		)
		(fp_text user "${REFERENCE}"
			(at -0.939 -4.599 90)
			(layer "B.Fab")
			(hide yes)
			(effects
				(font
					(size 0.7 0.7)
					(thickness 0.15)
				)
				(justify right top mirror)
			)
		)
		(fp_text user "Author: Antmicro"
			(at -0.939 -3.399 90)
			(layer "B.Fab")
			(hide yes)
			(effects
				(font
					(size 0.7 0.7)
					(thickness 0.15)
				)
				(justify right top mirror)
			)
		)
		(fp_text user "License: Apache-2.0"
			(at -0.939 -5.799 90)
			(layer "B.Fab")
			(hide yes)
			(effects
				(font
					(size 0.7 0.7)
					(thickness 0.15)
				)
				(justify right top mirror)
			)
		)
		(pad "1" smd roundrect
			(at -0.48 0 90)
			(size 0.59 0.64)
			(layers "B.Cu" "B.Paste" "B.Mask")
			(roundrect_rratio 0.25)
			(net 51 "GND")
			(pintype "passive")
		)
		(pad "2" smd roundrect
			(at 0.48 0 90)
			(size 0.59 0.64)
			(layers "B.Cu" "B.Paste" "B.Mask")
			(roundrect_rratio 0.25)
			(net 23 "+3V3")
			(pintype "passive")
		)
	)
	(footprint "antmicro-footprints:R_0402_1005Metric"
		(layer "B.Cu")
		(at 129.794 125.32775 180)
		(descr "Resistor SMD 0402")
		(tags "resistor SMD 0402")
		(property "Reference" "R24"
			(at -3.336 -0.46225 0)
			(layer "B.SilkS")
			(effects
				(font
					(size 0.7 0.7)
					(thickness 0.15)
				)
				(justify left bottom mirror)
			)
		)
		(property "Value" "R_1k_0402"
			(at -1.011843 -1.772047 0)
			(layer "B.Fab")
			(effects
				(font
					(size 0.7 0.7)
					(thickness 0.15)
				)
				(justify left bottom mirror)
			)
		)
		(property "Footprint" "antmicro-footprints:R_0402_1005Metric"
			(at 0 0 0)
			(layer "B.Fab")
			(hide yes)
			(effects
				(font
					(size 1.27 1.27)
					(thickness 0.15)
				)
				(justify mirror)
			)
		)
		(property "Datasheet" "https://www.bourns.com/docs/product-datasheets/cr.pdf"
			(at 0 0 0)
			(layer "B.Fab")
			(hide yes)
			(effects
				(font
					(size 1.27 1.27)
					(thickness 0.15)
				)
				(justify mirror)
			)
		)
		(property "Description" "SMD Chip Resistor, 1 kohm, ± 1%, 63 mW, 0402 [1005 Metric], Thick Film, General Purpose"
			(at 0 0 0)
			(layer "B.Fab")
			(hide yes)
			(effects
				(font
					(size 1.27 1.27)
					(thickness 0.15)
				)
				(justify mirror)
			)
		)
		(property "MPN" "CR0402-FX-1001GLF"
			(at 0 0 0)
			(unlocked yes)
			(layer "B.Fab")
			(hide yes)
			(effects
				(font
					(size 1 1)
					(thickness 0.15)
				)
				(justify mirror)
			)
		)
		(property "Manufacturer" "Bourns"
			(at 0 0 0)
			(unlocked yes)
			(layer "B.Fab")
			(hide yes)
			(effects
				(font
					(size 1 1)
					(thickness 0.15)
				)
				(justify mirror)
			)
		)
		(property "License" "Apache-2.0"
			(at 0 0 0)
			(unlocked yes)
			(layer "B.Fab")
			(hide yes)
			(effects
				(font
					(size 1 1)
					(thickness 0.15)
				)
				(justify mirror)
			)
		)
		(property "Author" "Antmicro"
			(at 0 0 0)
			(unlocked yes)
			(layer "B.Fab")
			(hide yes)
			(effects
				(font
					(size 1 1)
					(thickness 0.15)
				)
				(justify mirror)
			)
		)
		(property "Val" "1k"
			(at 0 0 0)
			(unlocked yes)
			(layer "B.Fab")
			(hide yes)
			(effects
				(font
					(size 1 1)
					(thickness 0.15)
				)
				(justify mirror)
			)
		)
		(property "Tolerance" "1%"
			(at 0 0 0)
			(unlocked yes)
			(layer "B.Fab")
			(hide yes)
			(effects
				(font
					(size 1 1)
					(thickness 0.15)
				)
				(justify mirror)
			)
		)
		(property "Public" "False"
			(at 0 0 0)
			(unlocked yes)
			(layer "B.Fab")
			(hide yes)
			(effects
				(font
					(size 1 1)
					(thickness 0.15)
				)
				(justify mirror)
			)
		)
		(sheetname "Root")
		(sheetfile "jetson-orin-baseboard-oculink-expansion.kicad_sch")
		(attr smd)
		(fp_rect
			(start -0.925 0.47)
			(end 0.925 -0.47)
			(stroke
				(width 0.05)
				(type default)
			)
			(fill none)
			(layer "B.CrtYd")
		)
		(fp_rect
			(start -0.5 0.25)
			(end 0.5 -0.25)
			(stroke
				(width 0.15)
				(type solid)
			)
			(fill none)
			(layer "B.Fab")
		)
		(fp_text user "License: Apache-2.0"
			(at -0.95 -5.169 0)
			(layer "B.Fab")
			(hide yes)
			(effects
				(font
					(size 0.7 0.7)
					(thickness 0.15)
				)
				(justify left bottom mirror)
			)
		)
		(fp_text user "${REFERENCE}"
			(at -0.95 -3.168 0)
			(layer "B.Fab")
			(hide yes)
			(effects
				(font
					(size 0.7 0.7)
					(thickness 0.15)
				)
				(justify left bottom mirror)
			)
		)
		(fp_text user "Author: Antmicro"
			(at -0.95 -4.169 0)
			(layer "B.Fab")
			(hide yes)
			(effects
				(font
					(size 0.7 0.7)
					(thickness 0.15)
				)
				(justify left bottom mirror)
			)
		)
		(pad "1" smd roundrect
			(at -0.48 0 180)
			(size 0.59 0.64)
			(layers "B.Cu" "B.Paste" "B.Mask")
			(roundrect_rratio 0.25)
			(net 51 "GND")
			(pintype "passive")
		)
		(pad "2" smd roundrect
			(at 0.48 0 180)
			(size 0.59 0.64)
			(layers "B.Cu" "B.Paste" "B.Mask")
			(roundrect_rratio 0.25)
			(net 99 "/TX_EQ2")
			(pintype "passive")
		)
	)
)
